(kicad_pcb
	(version 20260206)
	(generator "pcbnew")
	(generator_version "10.0")
	(general
		(thickness 1.6)
		(legacy_teardrops no)
	)
	(paper "A4")
	(title_block
		(title "03242023_DA0F0TMBIJ0_F0T_Motherboard_J_brd_V01_OCP.brd")
		(comment 1 "Grand Teton / footprints 2396-2403 of 6105")
	)
	(layers
		(0 "F.Cu" signal "TOP")
		(4 "In1.Cu" signal "GND")
		(6 "In2.Cu" signal "IN1")
		(8 "In3.Cu" signal "GND1")
		(10 "In4.Cu" signal "IN2")
		(12 "In5.Cu" signal "GND2")
		(14 "In6.Cu" signal "IN3")
		(16 "In7.Cu" signal "GND3")
		(18 "In8.Cu" signal "VCC")
		(20 "In9.Cu" signal "VCC1")
		(22 "In10.Cu" signal "GND4")
		(24 "In11.Cu" signal "IN4")
		(26 "In12.Cu" signal "GND5")
		(28 "In13.Cu" signal "IN5")
		(30 "In14.Cu" signal "GND6")
		(32 "In15.Cu" signal "IN6")
		(34 "In16.Cu" signal "GND7")
		(2 "B.Cu" signal "BOTTOM")
		(9 "F.Adhes" user "F.Adhesive")
		(11 "B.Adhes" user "B.Adhesive")
		(13 "F.Paste" user "Package Geometry/Pastemask Top")
		(15 "B.Paste" user "Package Geometry/Pastemask Bottom")
		(5 "F.SilkS" user "Ref Des/Silkscreen Top")
		(7 "B.SilkS" user "Ref Des/Silkscreen Bottom")
		(1 "F.Mask" user "Board Geometry/Soldermask Top")
		(3 "B.Mask" user "Board Geometry/Soldermask Bottom")
		(17 "Dwgs.User" user "User.Drawings")
		(19 "Cmts.User" user "User.Comments")
		(21 "Eco1.User" user "User.Eco1")
		(23 "Eco2.User" user "User.Eco2")
		(25 "Edge.Cuts" user "Board Geometry/Outline")
		(27 "Margin" user)
		(31 "F.CrtYd" user "Package Geometry/Place Bound Top")
		(29 "B.CrtYd" user "Package Geometry/Place Bound Bottom")
		(35 "F.Fab" user "Ref Des/Assembly Top")
		(33 "B.Fab" user "Ref Des/Assembly Bottom")
	)
	(footprint ""
		(layer "F.Cu")
		(at 242.92179 -249.281442 180)
		(property "Reference" "Y3"
			(at -0.22225 -3.369564 0)
			(unlocked yes)
			(layer "F.SilkS")
			(effects
				(font
					(size 0.7874 0.5842)
					(thickness 0.1524)
				)
				(justify left)
			)
		)
		(property "Value" ""
			(at 0 0 180)
			(layer "F.Fab")
			(effects
				(font
					(size 1.27 1.27)
				)
			)
		)
		(duplicate_pad_numbers_are_jumpers no)
		(fp_line
			(start 1.538732 1.937004)
			(end -1.538732 1.937004)
			(stroke
				(width 0.1524)
				(type default)
			)
			(layer "F.SilkS")
		)
		(fp_line
			(start 1.538732 -1.937004)
			(end 1.538732 1.937004)
			(stroke
				(width 0.1524)
				(type default)
			)
			(layer "F.SilkS")
		)
		(fp_line
			(start -1.538732 1.937004)
			(end -1.538732 -1.937004)
			(stroke
				(width 0.1524)
				(type default)
			)
			(layer "F.SilkS")
		)
		(fp_line
			(start -1.538732 -1.937004)
			(end 1.538732 -1.937004)
			(stroke
				(width 0.1524)
				(type default)
			)
			(layer "F.SilkS")
		)
		(fp_poly
			(pts
				(xy -1.724406 -1.059942) (xy -2.5908 -0.626872) (xy -2.5908 -1.493266)
			)
			(stroke
				(width 0)
				(type default)
			)
			(fill yes)
			(layer "F.SilkS")
		)
		(fp_line
			(start 1.299972 1.649984)
			(end -1.299972 1.649984)
			(stroke
				(width 0.1)
				(type default)
			)
			(layer "F.Fab")
		)
		(fp_line
			(start 1.299972 -1.649984)
			(end 1.299972 1.649984)
			(stroke
				(width 0.1)
				(type default)
			)
			(layer "F.Fab")
		)
		(fp_line
			(start -1.299972 1.649984)
			(end -1.299972 -1.649984)
			(stroke
				(width 0.1)
				(type default)
			)
			(layer "F.Fab")
		)
		(fp_line
			(start -1.299972 -1.649984)
			(end 1.299972 -1.649984)
			(stroke
				(width 0.1)
				(type default)
			)
			(layer "F.Fab")
		)
		(fp_poly
			(pts
				(xy -2.5908 -0.626872) (xy -2.5908 -1.493266) (xy -1.724406 -1.059942)
			)
			(stroke
				(width 0)
				(type default)
			)
			(fill yes)
			(layer "F.Fab")
		)
		(pad "1" smd rect
			(at -0.8001 -1.059942 180)
			(size 1.2192 1.4986)
			(layers "F.Cu" "F.Mask" "F.Paste")
			(net "CLK_GEN2_XTAL_IN_R")
		)
		(pad "2" smd rect
			(at -0.8001 1.059942 180)
			(size 1.2192 1.4986)
			(layers "F.Cu" "F.Mask" "F.Paste")
			(net "GND")
		)
		(pad "3" smd rect
			(at 0.8001 1.059942 180)
			(size 1.2192 1.4986)
			(layers "F.Cu" "F.Mask" "F.Paste")
			(net "CLK_GEN2_XTAL_OUT")
		)
		(pad "4" smd rect
			(at 0.8001 -1.059942 180)
			(size 1.2192 1.4986)
			(layers "F.Cu" "F.Mask" "F.Paste")
			(net "GND")
		)
	)
	(footprint ""
		(layer "F.Cu")
		(at 312.443622 -42.713148)
		(property "Reference" "R380"
			(at 0 0 0)
			(layer "F.SilkS")
			(hide yes)
			(effects
				(font
					(size 1.27 1.27)
				)
			)
		)
		(property "Value" ""
			(at 0 0 0)
			(layer "F.Fab")
			(effects
				(font
					(size 1.27 1.27)
				)
			)
		)
		(duplicate_pad_numbers_are_jumpers no)
		(fp_line
			(start -0.7874 -0.4064)
			(end 0.7874 -0.4064)
			(stroke
				(width 0.1524)
				(type default)
			)
			(layer "F.SilkS")
		)
		(fp_line
			(start -0.7874 0.4064)
			(end -0.7874 -0.4064)
			(stroke
				(width 0.1524)
				(type default)
			)
			(layer "F.SilkS")
		)
		(fp_line
			(start 0.7874 -0.4064)
			(end 0.7874 0.4064)
			(stroke
				(width 0.1524)
				(type default)
			)
			(layer "F.SilkS")
		)
		(fp_line
			(start 0.7874 0.4064)
			(end -0.7874 0.4064)
			(stroke
				(width 0.1524)
				(type default)
			)
			(layer "F.SilkS")
		)
		(fp_line
			(start -0.67945 -0.305054)
			(end -0.12065 -0.305054)
			(stroke
				(width 0.1)
				(type default)
			)
			(layer "F.Fab")
		)
		(fp_line
			(start -0.67945 0.3048)
			(end -0.67945 -0.305054)
			(stroke
				(width 0.1)
				(type default)
			)
			(layer "F.Fab")
		)
		(fp_line
			(start -0.12065 -0.305054)
			(end -0.12065 -0.2794)
			(stroke
				(width 0.1)
				(type default)
			)
			(layer "F.Fab")
		)
		(fp_line
			(start -0.12065 -0.2794)
			(end 0.12065 -0.2794)
			(stroke
				(width 0.1)
				(type default)
			)
			(layer "F.Fab")
		)
		(fp_line
			(start -0.12065 0.2794)
			(end -0.12065 0.3048)
			(stroke
				(width 0.1)
				(type default)
			)
			(layer "F.Fab")
		)
		(fp_line
			(start -0.12065 0.3048)
			(end -0.67945 0.3048)
			(stroke
				(width 0.1)
				(type default)
			)
			(layer "F.Fab")
		)
		(fp_line
			(start 0.120396 0.2794)
			(end -0.12065 0.2794)
			(stroke
				(width 0.1)
				(type default)
			)
			(layer "F.Fab")
		)
		(fp_line
			(start 0.120396 0.3048)
			(end 0.120396 0.2794)
			(stroke
				(width 0.1)
				(type default)
			)
			(layer "F.Fab")
		)
		(fp_line
			(start 0.12065 -0.3048)
			(end 0.67945 -0.3048)
			(stroke
				(width 0.1)
				(type default)
			)
			(layer "F.Fab")
		)
		(fp_line
			(start 0.12065 -0.2794)
			(end 0.12065 -0.3048)
			(stroke
				(width 0.1)
				(type default)
			)
			(layer "F.Fab")
		)
		(fp_line
			(start 0.67945 -0.3048)
			(end 0.67945 0.3048)
			(stroke
				(width 0.1)
				(type default)
			)
			(layer "F.Fab")
		)
		(fp_line
			(start 0.67945 0.3048)
			(end 0.120396 0.3048)
			(stroke
				(width 0.1)
				(type default)
			)
			(layer "F.Fab")
		)
		(pad "1" smd circle
			(at -0.40005 0)
			(size 0 0)
			(layers "F.Cu" "F.Mask" "F.Paste")
			(net "P3V3_AUX")
		)
		(pad "2" smd circle
			(at 0.40005 0)
			(size 0 0)
			(layers "F.Cu" "F.Mask" "F.Paste")
			(net "FM_FLASH_SECURITY_STRAP")
		)
	)
	(footprint ""
		(layer "F.Cu")
		(at 108.56722 -296.05478)
		(property "Reference" "C260"
			(at 0 0 0)
			(layer "F.SilkS")
			(hide yes)
			(effects
				(font
					(size 1.27 1.27)
				)
			)
		)
		(property "Value" ""
			(at 0 0 0)
			(layer "F.Fab")
			(effects
				(font
					(size 1.27 1.27)
				)
			)
		)
		(duplicate_pad_numbers_are_jumpers no)
		(fp_line
			(start -1.524 -0.762)
			(end 1.524 -0.762)
			(stroke
				(width 0.1524)
				(type default)
			)
			(layer "F.SilkS")
		)
		(fp_line
			(start -1.524 0.762)
			(end -1.524 -0.762)
			(stroke
				(width 0.1524)
				(type default)
			)
			(layer "F.SilkS")
		)
		(fp_line
			(start 1.524 -0.762)
			(end 1.524 0.762)
			(stroke
				(width 0.1524)
				(type default)
			)
			(layer "F.SilkS")
		)
		(fp_line
			(start 1.524 0.762)
			(end -1.524 0.762)
			(stroke
				(width 0.1524)
				(type default)
			)
			(layer "F.SilkS")
		)
		(fp_line
			(start -1.1049 -0.724916)
			(end -1.1049 0.724916)
			(stroke
				(width 0.1)
				(type default)
			)
			(layer "F.Fab")
		)
		(fp_line
			(start -1.1049 0.724916)
			(end 1.1049 0.724916)
			(stroke
				(width 0.1)
				(type default)
			)
			(layer "F.Fab")
		)
		(fp_line
			(start 1.1049 -0.724916)
			(end -1.1049 -0.724916)
			(stroke
				(width 0.1)
				(type default)
			)
			(layer "F.Fab")
		)
		(fp_line
			(start 1.1049 0.724916)
			(end 1.1049 -0.724916)
			(stroke
				(width 0.1)
				(type default)
			)
			(layer "F.Fab")
		)
		(pad "1" smd rect
			(at -0.889 0 180)
			(size 1.016 1.27)
			(layers "F.Cu" "F.Mask" "F.Paste")
			(net "PVCCIN_CPU1")
		)
		(pad "2" smd rect
			(at 0.889 0 180)
			(size 1.016 1.27)
			(layers "F.Cu" "F.Mask" "F.Paste")
			(net "GND")
		)
	)
	(footprint ""
		(layer "F.Cu")
		(at 446.18783 -376.471434)
		(property "Reference" "C1171"
			(at 0 0 0)
			(layer "F.SilkS")
			(hide yes)
			(effects
				(font
					(size 1.27 1.27)
				)
			)
		)
		(property "Value" ""
			(at 0 0 0)
			(layer "F.Fab")
			(effects
				(font
					(size 1.27 1.27)
				)
			)
		)
		(duplicate_pad_numbers_are_jumpers no)
		(fp_line
			(start -1.524 -0.762)
			(end 1.524 -0.762)
			(stroke
				(width 0.1524)
				(type default)
			)
			(layer "F.SilkS")
		)
		(fp_line
			(start -1.524 0.762)
			(end -1.524 -0.762)
			(stroke
				(width 0.1524)
				(type default)
			)
			(layer "F.SilkS")
		)
		(fp_line
			(start 1.524 -0.762)
			(end 1.524 0.762)
			(stroke
				(width 0.1524)
				(type default)
			)
			(layer "F.SilkS")
		)
		(fp_line
			(start 1.524 0.762)
			(end -1.524 0.762)
			(stroke
				(width 0.1524)
				(type default)
			)
			(layer "F.SilkS")
		)
		(fp_line
			(start -1.1049 -0.724916)
			(end -1.1049 0.724916)
			(stroke
				(width 0.1)
				(type default)
			)
			(layer "F.Fab")
		)
		(fp_line
			(start -1.1049 0.724916)
			(end 1.1049 0.724916)
			(stroke
				(width 0.1)
				(type default)
			)
			(layer "F.Fab")
		)
		(fp_line
			(start 1.1049 -0.724916)
			(end -1.1049 -0.724916)
			(stroke
				(width 0.1)
				(type default)
			)
			(layer "F.Fab")
		)
		(fp_line
			(start 1.1049 0.724916)
			(end 1.1049 -0.724916)
			(stroke
				(width 0.1)
				(type default)
			)
			(layer "F.Fab")
		)
		(pad "1" smd rect
			(at -0.889 0 180)
			(size 1.016 1.27)
			(layers "F.Cu" "F.Mask" "F.Paste")
			(net "P5V_AUX")
		)
		(pad "2" smd rect
			(at 0.889 0 180)
			(size 1.016 1.27)
			(layers "F.Cu" "F.Mask" "F.Paste")
			(net "GND")
		)
	)
	(footprint ""
		(layer "F.Cu")
		(at 396.518384 -16.088614 90)
		(property "Reference" "C842"
			(at 0 0 90)
			(layer "F.SilkS")
			(hide yes)
			(effects
				(font
					(size 1.27 1.27)
				)
			)
		)
		(property "Value" ""
			(at 0 0 90)
			(layer "F.Fab")
			(effects
				(font
					(size 1.27 1.27)
				)
			)
		)
		(duplicate_pad_numbers_are_jumpers no)
		(fp_line
			(start 0.299974 -0.150114)
			(end 0.299974 0.150114)
			(stroke
				(width 0.1)
				(type default)
			)
			(layer "F.Fab")
		)
		(fp_line
			(start -0.299974 -0.150114)
			(end 0.299974 -0.150114)
			(stroke
				(width 0.1)
				(type default)
			)
			(layer "F.Fab")
		)
		(fp_line
			(start 0.299974 0.150114)
			(end -0.299974 0.150114)
			(stroke
				(width 0.1)
				(type default)
			)
			(layer "F.Fab")
		)
		(fp_line
			(start -0.299974 0.150114)
			(end -0.299974 -0.150114)
			(stroke
				(width 0.1)
				(type default)
			)
			(layer "F.Fab")
		)
		(pad "1" smd rect
			(at -0.2667 0 90)
			(size 0.3048 0.381)
			(layers "F.Cu" "F.Mask" "F.Paste")
			(net "P5E_CPU0_PE1_TX_C_DN<13>")
		)
		(pad "2" smd rect
			(at 0.2667 0 90)
			(size 0.3048 0.381)
			(layers "F.Cu" "F.Mask" "F.Paste")
			(net "P5E_CPU0_PE1_TX_DN<13>")
		)
	)
	(footprint ""
		(layer "F.Cu")
		(at 107.019598 -17.13611)
		(property "Reference" "R3554"
			(at 0 0 0)
			(layer "F.SilkS")
			(hide yes)
			(effects
				(font
					(size 1.27 1.27)
				)
			)
		)
		(property "Value" ""
			(at 0 0 0)
			(layer "F.Fab")
			(effects
				(font
					(size 1.27 1.27)
				)
			)
		)
		(duplicate_pad_numbers_are_jumpers no)
		(fp_line
			(start -0.7874 -0.4064)
			(end 0.7874 -0.4064)
			(stroke
				(width 0.1524)
				(type default)
			)
			(layer "F.SilkS")
		)
		(fp_line
			(start -0.7874 0.4064)
			(end -0.7874 -0.4064)
			(stroke
				(width 0.1524)
				(type default)
			)
			(layer "F.SilkS")
		)
		(fp_line
			(start 0.7874 -0.4064)
			(end 0.7874 0.4064)
			(stroke
				(width 0.1524)
				(type default)
			)
			(layer "F.SilkS")
		)
		(fp_line
			(start 0.7874 0.4064)
			(end -0.7874 0.4064)
			(stroke
				(width 0.1524)
				(type default)
			)
			(layer "F.SilkS")
		)
		(fp_line
			(start -0.67945 -0.305054)
			(end -0.12065 -0.305054)
			(stroke
				(width 0.1)
				(type default)
			)
			(layer "F.Fab")
		)
		(fp_line
			(start -0.67945 0.3048)
			(end -0.67945 -0.305054)
			(stroke
				(width 0.1)
				(type default)
			)
			(layer "F.Fab")
		)
		(fp_line
			(start -0.12065 -0.305054)
			(end -0.12065 -0.2794)
			(stroke
				(width 0.1)
				(type default)
			)
			(layer "F.Fab")
		)
		(fp_line
			(start -0.12065 -0.2794)
			(end 0.12065 -0.2794)
			(stroke
				(width 0.1)
				(type default)
			)
			(layer "F.Fab")
		)
		(fp_line
			(start -0.12065 0.2794)
			(end -0.12065 0.3048)
			(stroke
				(width 0.1)
				(type default)
			)
			(layer "F.Fab")
		)
		(fp_line
			(start -0.12065 0.3048)
			(end -0.67945 0.3048)
			(stroke
				(width 0.1)
				(type default)
			)
			(layer "F.Fab")
		)
		(fp_line
			(start 0.120396 0.2794)
			(end -0.12065 0.2794)
			(stroke
				(width 0.1)
				(type default)
			)
			(layer "F.Fab")
		)
		(fp_line
			(start 0.120396 0.3048)
			(end 0.120396 0.2794)
			(stroke
				(width 0.1)
				(type default)
			)
			(layer "F.Fab")
		)
		(fp_line
			(start 0.12065 -0.3048)
			(end 0.67945 -0.3048)
			(stroke
				(width 0.1)
				(type default)
			)
			(layer "F.Fab")
		)
		(fp_line
			(start 0.12065 -0.2794)
			(end 0.12065 -0.3048)
			(stroke
				(width 0.1)
				(type default)
			)
			(layer "F.Fab")
		)
		(fp_line
			(start 0.67945 -0.3048)
			(end 0.67945 0.3048)
			(stroke
				(width 0.1)
				(type default)
			)
			(layer "F.Fab")
		)
		(fp_line
			(start 0.67945 0.3048)
			(end 0.120396 0.3048)
			(stroke
				(width 0.1)
				(type default)
			)
			(layer "F.Fab")
		)
		(pad "1" smd circle
			(at -0.40005 0)
			(size 0 0)
			(layers "F.Cu" "F.Mask" "F.Paste")
			(net "SMB_LM75_3_3V3AUX_SDA")
		)
		(pad "2" smd circle
			(at 0.40005 0)
			(size 0 0)
			(layers "F.Cu" "F.Mask" "F.Paste")
			(net "SMB_LM75_3_3V3AUX_SDA_R1")
		)
	)
	(footprint ""
		(layer "F.Cu")
		(at 27.0383 -127.348996 180)
		(property "Reference" "PC478"
			(at 0 0 180)
			(layer "F.SilkS")
			(hide yes)
			(effects
				(font
					(size 1.27 1.27)
				)
			)
		)
		(property "Value" ""
			(at 0 0 180)
			(layer "F.Fab")
			(effects
				(font
					(size 1.27 1.27)
				)
			)
		)
		(duplicate_pad_numbers_are_jumpers no)
		(fp_line
			(start 0.7874 0.4064)
			(end -0.7874 0.4064)
			(stroke
				(width 0.1524)
				(type default)
			)
			(layer "F.SilkS")
		)
		(fp_line
			(start 0.7874 -0.4064)
			(end 0.7874 0.4064)
			(stroke
				(width 0.1524)
				(type default)
			)
			(layer "F.SilkS")
		)
		(fp_line
			(start -0.7874 0.4064)
			(end -0.7874 -0.4064)
			(stroke
				(width 0.1524)
				(type default)
			)
			(layer "F.SilkS")
		)
		(fp_line
			(start -0.7874 -0.4064)
			(end 0.7874 -0.4064)
			(stroke
				(width 0.1524)
				(type default)
			)
			(layer "F.SilkS")
		)
		(fp_line
			(start 0.67945 0.3048)
			(end 0.120396 0.3048)
			(stroke
				(width 0.1)
				(type default)
			)
			(layer "F.Fab")
		)
		(fp_line
			(start 0.67945 -0.3048)
			(end 0.67945 0.3048)
			(stroke
				(width 0.1)
				(type default)
			)
			(layer "F.Fab")
		)
		(fp_line
			(start 0.12065 -0.2794)
			(end 0.12065 -0.3048)
			(stroke
				(width 0.1)
				(type default)
			)
			(layer "F.Fab")
		)
		(fp_line
			(start 0.12065 -0.3048)
			(end 0.67945 -0.3048)
			(stroke
				(width 0.1)
				(type default)
			)
			(layer "F.Fab")
		)
		(fp_line
			(start 0.120396 0.3048)
			(end 0.120396 0.2794)
			(stroke
				(width 0.1)
				(type default)
			)
			(layer "F.Fab")
		)
		(fp_line
			(start 0.120396 0.2794)
			(end -0.12065 0.2794)
			(stroke
				(width 0.1)
				(type default)
			)
			(layer "F.Fab")
		)
		(fp_line
			(start -0.12065 0.3048)
			(end -0.67945 0.3048)
			(stroke
				(width 0.1)
				(type default)
			)
			(layer "F.Fab")
		)
		(fp_line
			(start -0.12065 0.2794)
			(end -0.12065 0.3048)
			(stroke
				(width 0.1)
				(type default)
			)
			(layer "F.Fab")
		)
		(fp_line
			(start -0.12065 -0.2794)
			(end 0.12065 -0.2794)
			(stroke
				(width 0.1)
				(type default)
			)
			(layer "F.Fab")
		)
		(fp_line
			(start -0.12065 -0.305054)
			(end -0.12065 -0.2794)
			(stroke
				(width 0.1)
				(type default)
			)
			(layer "F.Fab")
		)
		(fp_line
			(start -0.67945 0.3048)
			(end -0.67945 -0.305054)
			(stroke
				(width 0.1)
				(type default)
			)
			(layer "F.Fab")
		)
		(fp_line
			(start -0.67945 -0.305054)
			(end -0.12065 -0.305054)
			(stroke
				(width 0.1)
				(type default)
			)
			(layer "F.Fab")
		)
		(pad "1" smd circle
			(at -0.40005 0 180)
			(size 0 0)
			(layers "F.Cu" "F.Mask" "F.Paste")
			(net "PVCCINFAON_CPU1_VCC")
		)
		(pad "2" smd circle
			(at 0.40005 0 180)
			(size 0 0)
			(layers "F.Cu" "F.Mask" "F.Paste")
			(net "GND")
		)
	)
	(footprint ""
		(layer "F.Cu")
		(at 118.09222 -419.920928 90)
		(property "Reference" "C1770"
			(at 0 0 90)
			(layer "F.SilkS")
			(hide yes)
			(effects
				(font
					(size 1.27 1.27)
				)
			)
		)
		(property "Value" ""
			(at 0 0 90)
			(layer "F.Fab")
			(effects
				(font
					(size 1.27 1.27)
				)
			)
		)
		(duplicate_pad_numbers_are_jumpers no)
		(fp_line
			(start 0.7874 -0.4064)
			(end 0.7874 0.4064)
			(stroke
				(width 0.1524)
				(type default)
			)
			(layer "F.SilkS")
		)
		(fp_line
			(start -0.7874 -0.4064)
			(end 0.7874 -0.4064)
			(stroke
				(width 0.1524)
				(type default)
			)
			(layer "F.SilkS")
		)
		(fp_line
			(start 0.7874 0.4064)
			(end -0.7874 0.4064)
			(stroke
				(width 0.1524)
				(type default)
			)
			(layer "F.SilkS")
		)
		(fp_line
			(start -0.7874 0.4064)
			(end -0.7874 -0.4064)
			(stroke
				(width 0.1524)
				(type default)
			)
			(layer "F.SilkS")
		)
		(fp_line
			(start -0.12065 -0.305054)
			(end -0.12065 -0.2794)
			(stroke
				(width 0.1)
				(type default)
			)
			(layer "F.Fab")
		)
		(fp_line
			(start -0.67945 -0.305054)
			(end -0.12065 -0.305054)
			(stroke
				(width 0.1)
				(type default)
			)
			(layer "F.Fab")
		)
		(fp_line
			(start 0.67945 -0.3048)
			(end 0.67945 0.3048)
			(stroke
				(width 0.1)
				(type default)
			)
			(layer "F.Fab")
		)
		(fp_line
			(start 0.12065 -0.3048)
			(end 0.67945 -0.3048)
			(stroke
				(width 0.1)
				(type default)
			)
			(layer "F.Fab")
		)
		(fp_line
			(start 0.12065 -0.2794)
			(end 0.12065 -0.3048)
			(stroke
				(width 0.1)
				(type default)
			)
			(layer "F.Fab")
		)
		(fp_line
			(start -0.12065 -0.2794)
			(end 0.12065 -0.2794)
			(stroke
				(width 0.1)
				(type default)
			)
			(layer "F.Fab")
		)
		(fp_line
			(start 0.120396 0.2794)
			(end -0.12065 0.2794)
			(stroke
				(width 0.1)
				(type default)
			)
			(layer "F.Fab")
		)
		(fp_line
			(start -0.12065 0.2794)
			(end -0.12065 0.3048)
			(stroke
				(width 0.1)
				(type default)
			)
			(layer "F.Fab")
		)
		(fp_line
			(start 0.67945 0.3048)
			(end 0.120396 0.3048)
			(stroke
				(width 0.1)
				(type default)
			)
			(layer "F.Fab")
		)
		(fp_line
			(start 0.120396 0.3048)
			(end 0.120396 0.2794)
			(stroke
				(width 0.1)
				(type default)
			)
			(layer "F.Fab")
		)
		(fp_line
			(start -0.12065 0.3048)
			(end -0.67945 0.3048)
			(stroke
				(width 0.1)
				(type default)
			)
			(layer "F.Fab")
		)
		(fp_line
			(start -0.67945 0.3048)
			(end -0.67945 -0.305054)
			(stroke
				(width 0.1)
				(type default)
			)
			(layer "F.Fab")
		)
		(pad "1" smd circle
			(at -0.40005 0 90)
			(size 0 0)
			(layers "F.Cu" "F.Mask" "F.Paste")
			(net "P3V3_AUX")
		)
		(pad "2" smd circle
			(at 0.40005 0 90)
			(size 0 0)
			(layers "F.Cu" "F.Mask" "F.Paste")
			(net "GND")
		)
	)
)
